# T6G (Grand Teton) — schematic netlist excerpt (pin names and nets, part order shuffled) for the footprints in the layout excerpt that follows; sources: Cadence DE-HDL packaged netlist, KiCad conversion of 04192023_DAF0TMB3IC0_F0TG_MB_C_brd_V02_OCP.brd

R4268  Q_RES  0 5% CHIP  pkg 0402LF  page 241 : A = PWRGD_P3V3_AUX_PDB ; B = PWRGD_P3V3_AUX_PDB_R
C1099  Q_CAP_DIFFBUS  DIFF BUS_0.22UF 6.3V 20% X6S  pkg C0201  page 67 : \1\ = P3E_CPU1_P4_TX_C_DN<3> ; \2\ = P3E_CPU1_P4_TX_DN<3>
R6272  Q_RES  200K 1% CHIP  pkg 0402LF  page 178 : A = USB_HUB2_MRP_CFG_STRAP ; B = GND

(kicad_pcb
	(version 20260206)
	(generator "pcbnew")
	(generator_version "10.0")
	(general
		(thickness 1.6)
		(legacy_teardrops no)
	)
	(paper "A4")
	(title_block
		(title "04192023_DAF0TMB3IC0_F0TG_MB_C_brd_V02_OCP.brd")
		(comment 1 "Grand Teton / footprints 3732-3734 of 8354")
	)
	(layers
		(0 "F.Cu" signal "TOP")
		(4 "In1.Cu" signal "GND")
		(6 "In2.Cu" signal "IN1")
		(8 "In3.Cu" signal "GND1")
		(10 "In4.Cu" signal "IN2")
		(12 "In5.Cu" signal "GND2")
		(14 "In6.Cu" signal "IN3")
		(16 "In7.Cu" signal "GND3")
		(18 "In8.Cu" signal "VCC")
		(20 "In9.Cu" signal "VCC1")
		(22 "In10.Cu" signal "GND4")
		(24 "In11.Cu" signal "IN4")
		(26 "In12.Cu" signal "GND5")
		(28 "In13.Cu" signal "IN5")
		(30 "In14.Cu" signal "GND6")
		(32 "In15.Cu" signal "IN6")
		(34 "In16.Cu" signal "GND7")
		(2 "B.Cu" signal "BOTTOM")
		(9 "F.Adhes" user "F.Adhesive")
		(11 "B.Adhes" user "B.Adhesive")
		(13 "F.Paste" user "Package Geometry/Pastemask Top")
		(15 "B.Paste" user "Package Geometry/Pastemask Bottom")
		(5 "F.SilkS" user "Ref Des/Silkscreen Top")
		(7 "B.SilkS" user "Ref Des/Silkscreen Bottom")
		(1 "F.Mask" user "Board Geometry/Soldermask Top")
		(3 "B.Mask" user "Board Geometry/Soldermask Bottom")
		(17 "Dwgs.User" user "User.Drawings")
		(19 "Cmts.User" user "User.Comments")
		(21 "Eco1.User" user "User.Eco1")
		(23 "Eco2.User" user "User.Eco2")
		(25 "Edge.Cuts" user "Board Geometry/Outline")
		(27 "Margin" user)
		(31 "F.CrtYd" user "Package Geometry/Place Bound Top")
		(29 "B.CrtYd" user "Package Geometry/Place Bound Bottom")
		(35 "F.Fab" user "Ref Des/Assembly Top")
		(33 "B.Fab" user "Ref Des/Assembly Bottom")
	)
	(footprint ""
		(layer "F.Cu")
		(at 281.905456 -434.655976 180)
		(property "Reference" "R4268"
			(at 0 0 180)
			(layer "F.SilkS")
			(hide yes)
			(effects
				(font
					(size 1.27 1.27)
				)
			)
		)
		(property "Value" ""
			(at 0 0 180)
			(layer "F.Fab")
			(effects
				(font
					(size 1.27 1.27)
				)
			)
		)
		(duplicate_pad_numbers_are_jumpers no)
		(fp_line
			(start 0.7874 0.4064)
			(end -0.7874 0.4064)
			(stroke
				(width 0.1524)
				(type default)
			)
			(layer "F.SilkS")
		)
		(fp_line
			(start 0.7874 -0.4064)
			(end 0.7874 0.4064)
			(stroke
				(width 0.1524)
				(type default)
			)
			(layer "F.SilkS")
		)
		(fp_line
			(start -0.7874 0.4064)
			(end -0.7874 -0.4064)
			(stroke
				(width 0.1524)
				(type default)
			)
			(layer "F.SilkS")
		)
		(fp_line
			(start -0.7874 -0.4064)
			(end 0.7874 -0.4064)
			(stroke
				(width 0.1524)
				(type default)
			)
			(layer "F.SilkS")
		)
		(fp_line
			(start 0.67945 0.3048)
			(end 0.120396 0.3048)
			(stroke
				(width 0.1)
				(type default)
			)
			(layer "F.Fab")
		)
		(fp_line
			(start 0.67945 -0.3048)
			(end 0.67945 0.3048)
			(stroke
				(width 0.1)
				(type default)
			)
			(layer "F.Fab")
		)
		(fp_line
			(start 0.12065 -0.2794)
			(end 0.12065 -0.3048)
			(stroke
				(width 0.1)
				(type default)
			)
			(layer "F.Fab")
		)
		(fp_line
			(start 0.12065 -0.3048)
			(end 0.67945 -0.3048)
			(stroke
				(width 0.1)
				(type default)
			)
			(layer "F.Fab")
		)
		(fp_line
			(start 0.120396 0.3048)
			(end 0.120396 0.2794)
			(stroke
				(width 0.1)
				(type default)
			)
			(layer "F.Fab")
		)
		(fp_line
			(start 0.120396 0.2794)
			(end -0.12065 0.2794)
			(stroke
				(width 0.1)
				(type default)
			)
			(layer "F.Fab")
		)
		(fp_line
			(start -0.12065 0.3048)
			(end -0.67945 0.3048)
			(stroke
				(width 0.1)
				(type default)
			)
			(layer "F.Fab")
		)
		(fp_line
			(start -0.12065 0.2794)
			(end -0.12065 0.3048)
			(stroke
				(width 0.1)
				(type default)
			)
			(layer "F.Fab")
		)
		(fp_line
			(start -0.12065 -0.2794)
			(end 0.12065 -0.2794)
			(stroke
				(width 0.1)
				(type default)
			)
			(layer "F.Fab")
		)
		(fp_line
			(start -0.12065 -0.305054)
			(end -0.12065 -0.2794)
			(stroke
				(width 0.1)
				(type default)
			)
			(layer "F.Fab")
		)
		(fp_line
			(start -0.67945 0.3048)
			(end -0.67945 -0.305054)
			(stroke
				(width 0.1)
				(type default)
			)
			(layer "F.Fab")
		)
		(fp_line
			(start -0.67945 -0.305054)
			(end -0.12065 -0.305054)
			(stroke
				(width 0.1)
				(type default)
			)
			(layer "F.Fab")
		)
		(pad "1" smd circle
			(at -0.40005 0 180)
			(size 0 0)
			(layers "F.Cu" "F.Mask" "F.Paste")
			(net "PWRGD_P3V3_AUX_PDB")
		)
		(pad "2" smd circle
			(at 0.40005 0 180)
			(size 0 0)
			(layers "F.Cu" "F.Mask" "F.Paste")
			(net "PWRGD_P3V3_AUX_PDB_R")
		)
	)
	(footprint ""
		(layer "F.Cu")
		(at 180.528468 -53.980334)
		(property "Reference" "C1099"
			(at 0 0 0)
			(layer "F.SilkS")
			(hide yes)
			(effects
				(font
					(size 1.27 1.27)
				)
			)
		)
		(property "Value" ""
			(at 0 0 0)
			(layer "F.Fab")
			(effects
				(font
					(size 1.27 1.27)
				)
			)
		)
		(duplicate_pad_numbers_are_jumpers no)
		(fp_line
			(start -0.299974 -0.150114)
			(end 0.299974 -0.150114)
			(stroke
				(width 0.1)
				(type default)
			)
			(layer "F.Fab")
		)
		(fp_line
			(start -0.299974 0.150114)
			(end -0.299974 -0.150114)
			(stroke
				(width 0.1)
				(type default)
			)
			(layer "F.Fab")
		)
		(fp_line
			(start 0.299974 -0.150114)
			(end 0.299974 0.150114)
			(stroke
				(width 0.1)
				(type default)
			)
			(layer "F.Fab")
		)
		(fp_line
			(start 0.299974 0.150114)
			(end -0.299974 0.150114)
			(stroke
				(width 0.1)
				(type default)
			)
			(layer "F.Fab")
		)
		(pad "1" smd rect
			(at -0.2667 0)
			(size 0.3048 0.381)
			(layers "F.Cu" "F.Mask" "F.Paste")
			(net "P3E_CPU1_P4_TX_C_DN<3>")
		)
		(pad "2" smd rect
			(at 0.2667 0)
			(size 0.3048 0.381)
			(layers "F.Cu" "F.Mask" "F.Paste")
			(net "P3E_CPU1_P4_TX_DN<3>")
		)
	)
	(footprint ""
		(layer "F.Cu")
		(at 109.136942 -19.9898 -90)
		(property "Reference" "R6272"
			(at 0 0 270)
			(layer "F.SilkS")
			(hide yes)
			(effects
				(font
					(size 1.27 1.27)
				)
			)
		)
		(property "Value" ""
			(at 0 0 270)
			(layer "F.Fab")
			(effects
				(font
					(size 1.27 1.27)
				)
			)
		)
		(duplicate_pad_numbers_are_jumpers no)
		(fp_line
			(start -0.7874 0.4064)
			(end -0.7874 -0.4064)
			(stroke
				(width 0.1524)
				(type default)
			)
			(layer "F.SilkS")
		)
		(fp_line
			(start 0.7874 0.4064)
			(end -0.7874 0.4064)
			(stroke
				(width 0.1524)
				(type default)
			)
			(layer "F.SilkS")
		)
		(fp_line
			(start -0.7874 -0.4064)
			(end 0.7874 -0.4064)
			(stroke
				(width 0.1524)
				(type default)
			)
			(layer "F.SilkS")
		)
		(fp_line
			(start 0.7874 -0.4064)
			(end 0.7874 0.4064)
			(stroke
				(width 0.1524)
				(type default)
			)
			(layer "F.SilkS")
		)
		(fp_line
			(start -0.67945 0.3048)
			(end -0.67945 -0.305054)
			(stroke
				(width 0.1)
				(type default)
			)
			(layer "F.Fab")
		)
		(fp_line
			(start -0.12065 0.3048)
			(end -0.67945 0.3048)
			(stroke
				(width 0.1)
				(type default)
			)
			(layer "F.Fab")
		)
		(fp_line
			(start 0.120396 0.3048)
			(end 0.120396 0.2794)
			(stroke
				(width 0.1)
				(type default)
			)
			(layer "F.Fab")
		)
		(fp_line
			(start 0.67945 0.3048)
			(end 0.120396 0.3048)
			(stroke
				(width 0.1)
				(type default)
			)
			(layer "F.Fab")
		)
		(fp_line
			(start -0.12065 0.2794)
			(end -0.12065 0.3048)
			(stroke
				(width 0.1)
				(type default)
			)
			(layer "F.Fab")
		)
		(fp_line
			(start 0.120396 0.2794)
			(end -0.12065 0.2794)
			(stroke
				(width 0.1)
				(type default)
			)
			(layer "F.Fab")
		)
		(fp_line
			(start -0.12065 -0.2794)
			(end 0.12065 -0.2794)
			(stroke
				(width 0.1)
				(type default)
			)
			(layer "F.Fab")
		)
		(fp_line
			(start 0.12065 -0.2794)
			(end 0.12065 -0.3048)
			(stroke
				(width 0.1)
				(type default)
			)
			(layer "F.Fab")
		)
		(fp_line
			(start 0.12065 -0.3048)
			(end 0.67945 -0.3048)
			(stroke
				(width 0.1)
				(type default)
			)
			(layer "F.Fab")
		)
		(fp_line
			(start 0.67945 -0.3048)
			(end 0.67945 0.3048)
			(stroke
				(width 0.1)
				(type default)
			)
			(layer "F.Fab")
		)
		(fp_line
			(start -0.67945 -0.305054)
			(end -0.12065 -0.305054)
			(stroke
				(width 0.1)
				(type default)
			)
			(layer "F.Fab")
		)
		(fp_line
			(start -0.12065 -0.305054)
			(end -0.12065 -0.2794)
			(stroke
				(width 0.1)
				(type default)
			)
			(layer "F.Fab")
		)
		(pad "1" smd circle
			(at -0.40005 0 270)
			(size 0 0)
			(layers "F.Cu" "F.Mask" "F.Paste")
			(net "USB_HUB2_MRP_CFG_STRAP")
		)
		(pad "2" smd circle
			(at 0.40005 0 270)
			(size 0 0)
			(layers "F.Cu" "F.Mask" "F.Paste")
			(net "GND")
		)
	)
)
